# BASEBOARD_FAB2 (Tioga Pass) — schematic netlist excerpt (pin names and nets, part order shuffled) for the footprints in the layout excerpt that follows; sources: Cadence DE-HDL packaged netlist, KiCad conversion of Wiwynn_Tioga_Pass_MB.brd

J1A2  SCONN288_H44441004  SCONN  pkg PIP  page 85
  \12v\(1)  = P12V_NVDIMM_KLM
  VSS(93)  = GND
  DQ(4)  = M_L_DQ<5>
  VSS(92)  = GND
  DQ(0)  = M_L_DQ<1>
  VSS(91)  = GND
  DQS9P  = M_L_DQS_DP<9>
  DQS9N  = M_L_DQS_DN<9>
  VSS(90)  = GND
  DQ(6)  = M_L_DQ<7>
  VSS(89)  = GND
  DQ(2)  = M_L_DQ<3>
  VSS(88)  = GND
  DQ(12)  = M_L_DQ<13>
  VSS(87)  = GND
  DQ(8)  = M_L_DQ<9>
  VSS(86)  = GND
  DQS10P  = M_L_DQS_DP<10>
  DQS10N  = M_L_DQS_DN<10>
  VSS(85)  = GND
  DQ(14)  = M_L_DQ<15>
  VSS(84)  = GND
  DQ(10)  = M_L_DQ<11>
  VSS(83)  = GND
  DQ(20)  = M_L_DQ<21>
  VSS(82)  = GND
  DQ(16)  = M_L_DQ<17>
  VSS(81)  = GND
  DQS11P  = M_L_DQS_DP<11>
  DQS11N  = M_L_DQS_DN<11>
  VSS(80)  = GND
  DQ(22)  = M_L_DQ<23>
  VSS(79)  = GND
  DQ(18)  = M_L_DQ<19>
  VSS(78)  = GND
  DQ(28)  = M_L_DQ<29>
  VSS(77)  = GND
  DQ(24)  = M_L_DQ<25>
  VSS(76)  = GND
  DQS12P  = M_L_DQS_DP<12>
  DQS12N  = M_L_DQS_DN<12>
  VSS(75)  = GND
  DQ(30)  = M_L_DQ<31>
  VSS(74)  = GND
  DQ(26)  = M_L_DQ<27>
  VSS(73)  = GND
  CB(4)  = M_L_ECC<5>
  VSS(72)  = GND
  CB(0)  = M_L_ECC<1>
  VSS(71)  = GND
  DQS17P  = M_L_DQS_DP<17>
  DQS17N  = M_L_DQS_DN<17>
  VSS(70)  = GND
  CB(6)  = M_L_ECC<7>
  VSS(69)  = GND
  CB(2)  = M_L_ECC<3>
  VSS(68)  = GND
  RESET_N  = M_KLM_RST_N
  VDD(25)  = PVDDQ_KLM
  CKE(0)  = M_L_CKE<0>
  VDD(24)  = PVDDQ_KLM
  ACT_N  = M_L_ACT_N
  BG(0)  = M_L_BG<0>
  VDD(23)  = PVDDQ_KLM
  A12  = M_L_MA<12>
  A9  = M_L_MA<9>
  VDD(22)  = PVDDQ_KLM
  A8  = M_L_MA<8>
  A6  = M_L_MA<6>
  VDD(21)  = PVDDQ_KLM
  A3  = M_L_MA<3>
  A1  = M_L_MA<1>
  VDD(20)  = PVDDQ_KLM
  CK0P  = M_L_CLK_DP<0>
  CK0N  = M_L_CLK_DN<0>
  VDD(19)  = PVDDQ_KLM
  VTT(1)  = PVTT_KLM
  EVENT_N  = FM_DIMM_EVENT_COD_N
  A0  = M_L_MA<0>
  VDD(18)  = PVDDQ_KLM
  BA(0)  = M_L_BA<0>
  A16_RAS_N  = M_L_MA<16>
  VDD(17)  = PVDDQ_KLM
  S0_N  = M_L_CS_N<0>
  VDD(16)  = PVDDQ_KLM
  A15_CAS_N  = M_L_MA<15>
  ODT(0)  = M_L_ODT<0>
  VDD(15)  = PVDDQ_KLM
  S1_N  = M_L_CS_N<1>
  VDD(14)  = PVDDQ_KLM
  ODT(1)  = M_L_ODT<1>
  VDD(13)  = PVDDQ_KLM
  S2_N_C(0)  = M_L_CS_N<2>
  VSS(67)  = GND
  DQ(36)  = M_L_DQ<37>
  VSS(66)  = GND
  DQ(32)  = M_L_DQ<33>
  VSS(65)  = GND
  DQS13P  = M_L_DQS_DP<13>
  DQS13N  = M_L_DQS_DN<13>
  VSS(64)  = GND
  DQ(38)  = M_L_DQ<39>
  VSS(63)  = GND
  DQ(34)  = M_L_DQ<35>
  VSS(62)  = GND
  DQ(44)  = M_L_DQ<45>
  VSS(61)  = GND
  DQ(40)  = M_L_DQ<41>
  VSS(60)  = GND
  DQS14P  = M_L_DQS_DP<14>
  DQS14N  = M_L_DQS_DN<14>
  VSS(59)  = GND
  DQ(46)  = M_L_DQ<47>
  VSS(58)  = GND
  DQ(42)  = M_L_DQ<43>
  VSS(57)  = GND
  DQ(52)  = M_L_DQ<53>
  VSS(56)  = GND
  DQ(48)  = M_L_DQ<49>
  VSS(55)  = GND
  DQS15P  = M_L_DQS_DP<15>
  DQS15N  = M_L_DQS_DN<15>
  VSS(54)  = GND
  DQ(54)  = M_L_DQ<55>
  VSS(53)  = GND
  DQ(50)  = M_L_DQ<51>
  VSS(52)  = GND
  DQ(60)  = M_L_DQ<61>
  VSS(51)  = GND
  DQ(56)  = M_L_DQ<57>
  VSS(50)  = GND
  DQS16P  = M_L_DQS_DP<16>
  DQS16N  = M_L_DQS_DN<16>
  VSS(49)  = GND
  DQ(62)  = M_L_DQ<63>
  VSS(48)  = GND
  DQ(58)  = M_L_DQ<59>
  VSS(47)  = GND
  SA(0)  = GND
  SA(1)  = PVPP_KLM
  SCL  = SMB_DDR_KLM_VPP_SCL
  VPP(4)  = PVPP_KLM
  VPP(3)  = PVPP_KLM
  RFU(2)  = TP_CH_L_DIMM_L0_RFU_2
  \12v\(0)  = P12V_NVDIMM_KLM
  VREFCA  = M_L_VREF
  VSS(46)  = GND
  DQ(5)  = M_L_DQ<4>
  VSS(45)  = GND
  DQ(1)  = M_L_DQ<0>
  VSS(44)  = GND
  DQS0N  = M_L_DQS_DN<0>
  DQS0P  = M_L_DQS_DP<0>
  VSS(43)  = GND
  DQ(7)  = M_L_DQ<6>
  VSS(42)  = GND
  DQ(3)  = M_L_DQ<2>
  VSS(41)  = GND
  DQ(13)  = M_L_DQ<12>
  VSS(40)  = GND
  DQ(9)  = M_L_DQ<8>
  VSS(39)  = GND
  DQS1N  = M_L_DQS_DN<1>
  DQS1P  = M_L_DQS_DP<1>
  VSS(38)  = GND
  DQ(15)  = M_L_DQ<14>
  VSS(37)  = GND
  DQ(11)  = M_L_DQ<10>
  VSS(36)  = GND
  DQ(21)  = M_L_DQ<20>
  VSS(35)  = GND
  DQ(17)  = M_L_DQ<16>
  VSS(34)  = GND
  DQS2N  = M_L_DQS_DN<2>
  DQS2P  = M_L_DQS_DP<2>
  VSS(33)  = GND
  DQ(23)  = M_L_DQ<22>
  VSS(32)  = GND
  DQ(19)  = M_L_DQ<18>
  VSS(31)  = GND
  DQ(29)  = M_L_DQ<28>
  VSS(30)  = GND
  DQ(25)  = M_L_DQ<24>
  VSS(29)  = GND
  DQS3N  = M_L_DQS_DN<3>
  DQS3P  = M_L_DQS_DP<3>
  VSS(28)  = GND
  DQ(31)  = M_L_DQ<30>
  VSS(27)  = GND
  DQ(27)  = M_L_DQ<26>
  VSS(26)  = GND
  CB(5)  = M_L_ECC<4>
  VSS(25)  = GND
  CB(1)  = M_L_ECC<0>
  VSS(24)  = GND
  DQS8N  = M_L_DQS_DN<8>
  DQS8P  = M_L_DQS_DP<8>
  VSS(23)  = GND
  CB(7)  = M_L_ECC<6>
  VSS(22)  = GND
  CB(3)  = M_L_ECC<2>
  VSS(21)  = GND
  CKE(1)  = M_L_CKE<1>
  VDD(12)  = PVDDQ_KLM
  RFU(0)  = TP_CH_L_DIMM_L0_RFU_0
  VDD(11)  = PVDDQ_KLM
  BG(1)  = M_L_BG<1>
  ALERT_N  = M_L_ALERT_N
  VDD(10)  = PVDDQ_KLM
  A11  = M_L_MA<11>
  A7  = M_L_MA<7>
  VDD(9)  = PVDDQ_KLM
  A5  = M_L_MA<5>
  A4  = M_L_MA<4>
  VDD(8)  = PVDDQ_KLM
  A2  = M_L_MA<2>
  VDD(7)  = PVDDQ_KLM
  CK1P  = M_L_CLK_DP<1>
  CK1N  = M_L_CLK_DN<1>
  VDD(6)  = PVDDQ_KLM
  VTT(0)  = PVTT_KLM
  PAR  = M_L_PAR
  VDD(5)  = PVDDQ_KLM
  BA(1)  = M_L_BA<1>
  A10  = M_L_MA<10>
  VDD(4)  = PVDDQ_KLM
  RFU(1)  = TP_CH_L_DIMM_L0_RFU_1
  A14_WE_N  = M_L_MA<14>
  VDD(3)  = PVDDQ_KLM
  SAVE_N_NC  = FM_ADR_COMPLETE_KLM_N
  VDD(2)  = PVDDQ_KLM
  A13  = M_L_MA<13>
  VDD(1)  = PVDDQ_KLM
  A17  = M_L_MA<17>
  C(2)  = M_L_C<2>
  VDD(0)  = PVDDQ_KLM
  S3_N_C(1)  = M_L_CS_N<3>
  SA(2)  = GND
  VSS(20)  = GND
  DQ(37)  = M_L_DQ<36>
  VSS(19)  = GND
  DQ(33)  = M_L_DQ<32>
  VSS(18)  = GND
  DQS4N  = M_L_DQS_DN<4>
  DQS4P  = M_L_DQS_DP<4>
  VSS(17)  = GND
  DQ(39)  = M_L_DQ<38>
  VSS(16)  = GND
  DQ(35)  = M_L_DQ<34>
  VSS(15)  = GND
  DQ(45)  = M_L_DQ<44>
  VSS(14)  = GND
  DQ(41)  = M_L_DQ<40>
  VSS(13)  = GND
  DQS5N  = M_L_DQS_DN<5>
  DQS5P  = M_L_DQS_DP<5>
  VSS(12)  = GND
  DQ(47)  = M_L_DQ<46>
  VSS(11)  = GND
  DQ(43)  = M_L_DQ<42>
  VSS(10)  = GND
  DQ(53)  = M_L_DQ<52>
  VSS(9)  = GND
  DQ(49)  = M_L_DQ<48>
  VSS(8)  = GND
  DQS6N  = M_L_DQS_DN<6>
  DQS6P  = M_L_DQS_DP<6>
  VSS(7)  = GND
  DQ(55)  = M_L_DQ<54>
  VSS(6)  = GND
  DQ(51)  = M_L_DQ<50>
  VSS(5)  = GND
  DQ(61)  = M_L_DQ<60>
  VSS(4)  = GND
  DQ(57)  = M_L_DQ<56>
  VSS(3)  = GND
  DQS7N  = M_L_DQS_DN<7>
  DQS7P  = M_L_DQS_DP<7>
  VSS(2)  = GND
  DQ(63)  = M_L_DQ<62>
  VSS(1)  = GND
  DQ(59)  = M_L_DQ<58>
  VSS(0)  = GND
  VDDSPD  = PVPP_KLM
  SDA  = SMB_DDR_KLM_VPP_SDA
  VPP(1)  = PVPP_KLM
  VPP(0)  = PVPP_KLM
  VPP(2)  = PVPP_KLM

(kicad_pcb
	(version 20260206)
	(generator "pcbnew")
	(generator_version "10.0")
	(general
		(thickness 1.6)
		(legacy_teardrops no)
	)
	(paper "A4")
	(title_block
		(title "Wiwynn_Tioga_Pass_MB.brd")
		(comment 1 "Tioga Pass / footprint 2031 of 4770 (J1A2), pads 52-101 of 291")
	)
	(layers
		(0 "F.Cu" signal "TOP")
		(4 "In1.Cu" signal "L2GND")
		(6 "In2.Cu" signal "L3")
		(8 "In3.Cu" signal "L4GND")
		(10 "In4.Cu" signal "L5")
		(12 "In5.Cu" signal "L6GND")
		(14 "In6.Cu" signal "L7VCC")
		(16 "In7.Cu" signal "L8VCC")
		(18 "In8.Cu" signal "L9GND")
		(20 "In9.Cu" signal "L10")
		(22 "In10.Cu" signal "L11GND")
		(24 "In11.Cu" signal "L12")
		(26 "In12.Cu" signal "L13GND")
		(2 "B.Cu" signal "BOTTOM")
		(9 "F.Adhes" user "F.Adhesive")
		(11 "B.Adhes" user "B.Adhesive")
		(13 "F.Paste" user "Package Geometry/Pastemask Top")
		(15 "B.Paste" user "Package Geometry/Pastemask Bottom")
		(5 "F.SilkS" user "Ref Des/Silkscreen Top")
		(7 "B.SilkS" user "Ref Des/Silkscreen Bottom")
		(1 "F.Mask" user "Board Geometry/Soldermask Top")
		(3 "B.Mask" user "Board Geometry/Soldermask Bottom")
		(17 "Dwgs.User" user "User.Drawings")
		(19 "Cmts.User" user "User.Comments")
		(21 "Eco1.User" user "User.Eco1")
		(23 "Eco2.User" user "User.Eco2")
		(25 "Edge.Cuts" user "Board Geometry/Outline")
		(27 "Margin" user)
		(31 "F.CrtYd" user "Package Geometry/Place Bound Top")
		(29 "B.CrtYd" user "Package Geometry/Place Bound Bottom")
		(35 "F.Fab" user "Ref Des/Assembly Top")
		(33 "B.Fab" user "Ref Des/Assembly Bottom")
	)
	(footprint ""
		(layer "F.Cu")
		(at 29.699458 -142.6718 90)
		(property "Reference" "J1A2"
			(at -2.623312 42.436542 0)
			(unlocked yes)
			(layer "F.SilkS")
			(effects
				(font
					(size 0.7874 0.5842)
					(thickness 0.1524)
				)
				(justify left)
			)
		)
		(property "Value" ""
			(at 0 0 90)
			(layer "F.Fab")
			(effects
				(font
					(size 1.27 1.27)
				)
			)
		)
		(duplicate_pad_numbers_are_jumpers no)
		(pad "49" smd rect
			(at 0 40.80002 90)
			(size 1.8034 0.508)
			(layers "F.Cu" "F.Mask" "F.Paste")
			(net "M_L_ECC<1>")
		)
		(pad "50" smd rect
			(at 0 41.649904 90)
			(size 1.8034 0.508)
			(layers "F.Cu" "F.Mask" "F.Paste")
			(net "GND")
		)
		(pad "51" smd rect
			(at 0 42.500042 90)
			(size 1.8034 0.508)
			(layers "F.Cu" "F.Mask" "F.Paste")
			(net "M_L_DQS_DP<17>")
		)
		(pad "52" smd rect
			(at 0 43.349926 90)
			(size 1.8034 0.508)
			(layers "F.Cu" "F.Mask" "F.Paste")
			(net "M_L_DQS_DN<17>")
		)
		(pad "53" smd rect
			(at 0 44.200064 90)
			(size 1.8034 0.508)
			(layers "F.Cu" "F.Mask" "F.Paste")
			(net "GND")
		)
		(pad "54" smd rect
			(at 0 45.049948 90)
			(size 1.8034 0.508)
			(layers "F.Cu" "F.Mask" "F.Paste")
			(net "M_L_ECC<7>")
		)
		(pad "55" smd rect
			(at 0 45.900086 90)
			(size 1.8034 0.508)
			(layers "F.Cu" "F.Mask" "F.Paste")
			(net "GND")
		)
		(pad "56" smd rect
			(at 0 46.74997 90)
			(size 1.8034 0.508)
			(layers "F.Cu" "F.Mask" "F.Paste")
			(net "M_L_ECC<3>")
		)
		(pad "57" smd rect
			(at 0 47.600108 90)
			(size 1.8034 0.508)
			(layers "F.Cu" "F.Mask" "F.Paste")
			(net "GND")
		)
		(pad "58" smd rect
			(at 0 48.449992 90)
			(size 1.8034 0.508)
			(layers "F.Cu" "F.Mask" "F.Paste")
			(net "M_KLM_RST_N")
		)
		(pad "59" smd rect
			(at 0 49.299876 90)
			(size 1.8034 0.508)
			(layers "F.Cu" "F.Mask" "F.Paste")
			(net "PVDDQ_KLM")
		)
		(pad "60" smd rect
			(at 0 50.150014 90)
			(size 1.8034 0.508)
			(layers "F.Cu" "F.Mask" "F.Paste")
			(net "M_L_CKE<0>")
		)
		(pad "61" smd rect
			(at 0 50.999898 90)
			(size 1.8034 0.508)
			(layers "F.Cu" "F.Mask" "F.Paste")
			(net "PVDDQ_KLM")
		)
		(pad "62" smd rect
			(at 0 51.850036 90)
			(size 1.8034 0.508)
			(layers "F.Cu" "F.Mask" "F.Paste")
			(net "M_L_ACT_N")
		)
		(pad "63" smd rect
			(at 0 52.69992 90)
			(size 1.8034 0.508)
			(layers "F.Cu" "F.Mask" "F.Paste")
			(net "M_L_BG<0>")
		)
		(pad "64" smd rect
			(at 0 53.550058 90)
			(size 1.8034 0.508)
			(layers "F.Cu" "F.Mask" "F.Paste")
			(net "PVDDQ_KLM")
		)
		(pad "65" smd rect
			(at 0 54.399942 90)
			(size 1.8034 0.508)
			(layers "F.Cu" "F.Mask" "F.Paste")
			(net "M_L_MA<12>")
		)
		(pad "66" smd rect
			(at 0 55.25008 90)
			(size 1.8034 0.508)
			(layers "F.Cu" "F.Mask" "F.Paste")
			(net "M_L_MA<9>")
		)
		(pad "67" smd rect
			(at 0 56.099964 90)
			(size 1.8034 0.508)
			(layers "F.Cu" "F.Mask" "F.Paste")
			(net "PVDDQ_KLM")
		)
		(pad "68" smd rect
			(at 0 56.950102 90)
			(size 1.8034 0.508)
			(layers "F.Cu" "F.Mask" "F.Paste")
			(net "M_L_MA<8>")
		)
		(pad "69" smd rect
			(at 0 57.799986 90)
			(size 1.8034 0.508)
			(layers "F.Cu" "F.Mask" "F.Paste")
			(net "M_L_MA<6>")
		)
		(pad "70" smd rect
			(at 0 58.650124 90)
			(size 1.8034 0.508)
			(layers "F.Cu" "F.Mask" "F.Paste")
			(net "PVDDQ_KLM")
		)
		(pad "71" smd rect
			(at 0 59.500008 90)
			(size 1.8034 0.508)
			(layers "F.Cu" "F.Mask" "F.Paste")
			(net "M_L_MA<3>")
		)
		(pad "72" smd rect
			(at 0 60.349892 90)
			(size 1.8034 0.508)
			(layers "F.Cu" "F.Mask" "F.Paste")
			(net "M_L_MA<1>")
		)
		(pad "73" smd rect
			(at 0 61.20003 90)
			(size 1.8034 0.508)
			(layers "F.Cu" "F.Mask" "F.Paste")
			(net "PVDDQ_KLM")
		)
		(pad "74" smd rect
			(at 0 62.049914 90)
			(size 1.8034 0.508)
			(layers "F.Cu" "F.Mask" "F.Paste")
			(net "M_L_CLK_DP<0>")
		)
		(pad "75" smd rect
			(at 0 62.900052 90)
			(size 1.8034 0.508)
			(layers "F.Cu" "F.Mask" "F.Paste")
			(net "M_L_CLK_DN<0>")
		)
		(pad "76" smd rect
			(at 0 63.749936 90)
			(size 1.8034 0.508)
			(layers "F.Cu" "F.Mask" "F.Paste")
			(net "PVDDQ_KLM")
		)
		(pad "77" smd rect
			(at 0 64.600074 90)
			(size 1.8034 0.508)
			(layers "F.Cu" "F.Mask" "F.Paste")
			(net "PVTT_KLM")
		)
		(pad "78" smd rect
			(at 0 70.550024 90)
			(size 1.8034 0.508)
			(layers "F.Cu" "F.Mask" "F.Paste")
			(net "FM_DIMM_EVENT_COD_N")
		)
		(pad "79" smd rect
			(at 0 71.399908 90)
			(size 1.8034 0.508)
			(layers "F.Cu" "F.Mask" "F.Paste")
			(net "M_L_MA<0>")
		)
		(pad "80" smd rect
			(at 0 72.250046 90)
			(size 1.8034 0.508)
			(layers "F.Cu" "F.Mask" "F.Paste")
			(net "PVDDQ_KLM")
		)
		(pad "81" smd rect
			(at 0 73.09993 90)
			(size 1.8034 0.508)
			(layers "F.Cu" "F.Mask" "F.Paste")
			(net "M_L_BA<0>")
		)
		(pad "82" smd rect
			(at 0 73.950068 90)
			(size 1.8034 0.508)
			(layers "F.Cu" "F.Mask" "F.Paste")
			(net "M_L_MA<16>")
		)
		(pad "83" smd rect
			(at 0 74.799952 90)
			(size 1.8034 0.508)
			(layers "F.Cu" "F.Mask" "F.Paste")
			(net "PVDDQ_KLM")
		)
		(pad "84" smd rect
			(at 0 75.65009 90)
			(size 1.8034 0.508)
			(layers "F.Cu" "F.Mask" "F.Paste")
			(net "M_L_CS_N<0>")
		)
		(pad "85" smd rect
			(at 0 76.499974 90)
			(size 1.8034 0.508)
			(layers "F.Cu" "F.Mask" "F.Paste")
			(net "PVDDQ_KLM")
		)
		(pad "86" smd rect
			(at 0 77.350112 90)
			(size 1.8034 0.508)
			(layers "F.Cu" "F.Mask" "F.Paste")
			(net "M_L_MA<15>")
		)
		(pad "87" smd rect
			(at 0 78.199996 90)
			(size 1.8034 0.508)
			(layers "F.Cu" "F.Mask" "F.Paste")
			(net "M_L_ODT<0>")
		)
		(pad "88" smd rect
			(at 0 79.04988 90)
			(size 1.8034 0.508)
			(layers "F.Cu" "F.Mask" "F.Paste")
			(net "PVDDQ_KLM")
		)
		(pad "89" smd rect
			(at 0 79.900018 90)
			(size 1.8034 0.508)
			(layers "F.Cu" "F.Mask" "F.Paste")
			(net "M_L_CS_N<1>")
		)
		(pad "90" smd rect
			(at 0 80.749902 90)
			(size 1.8034 0.508)
			(layers "F.Cu" "F.Mask" "F.Paste")
			(net "PVDDQ_KLM")
		)
		(pad "91" smd rect
			(at 0 81.60004 90)
			(size 1.8034 0.508)
			(layers "F.Cu" "F.Mask" "F.Paste")
			(net "M_L_ODT<1>")
		)
		(pad "92" smd rect
			(at 0 82.449924 90)
			(size 1.8034 0.508)
			(layers "F.Cu" "F.Mask" "F.Paste")
			(net "PVDDQ_KLM")
		)
		(pad "93" smd rect
			(at 0 83.300062 90)
			(size 1.8034 0.508)
			(layers "F.Cu" "F.Mask" "F.Paste")
			(net "M_L_CS_N<2>")
		)
		(pad "94" smd rect
			(at 0 84.149946 90)
			(size 1.8034 0.508)
			(layers "F.Cu" "F.Mask" "F.Paste")
			(net "GND")
		)
		(pad "95" smd rect
			(at 0 85.000084 90)
			(size 1.8034 0.508)
			(layers "F.Cu" "F.Mask" "F.Paste")
			(net "M_L_DQ<37>")
		)
		(pad "96" smd rect
			(at 0 85.849968 90)
			(size 1.8034 0.508)
			(layers "F.Cu" "F.Mask" "F.Paste")
			(net "GND")
		)
		(pad "97" smd rect
			(at 0 86.700106 90)
			(size 1.8034 0.508)
			(layers "F.Cu" "F.Mask" "F.Paste")
			(net "M_L_DQ<33>")
		)
		(pad "98" smd rect
			(at 0 87.54999 90)
			(size 1.8034 0.508)
			(layers "F.Cu" "F.Mask" "F.Paste")
			(net "GND")
		)
	)
)
